FILE_TYPE=LIBRARY_PARTS;
primitive 'SCONN288_DDR506112002KQ';
  pin
    'VIN_MGMT':
      PIN_NUMBER='(3,0,0)';
      PINUSE='POWER';
      NO_LOAD_CHECK='Both';
      NO_IO_CHECK='Both';
      NO_ASSERT_CHECK='TRUE';
      NO_DIR_CHECK='TRUE';
      ALLOW_CONNECT='TRUE';
    'RFU0':
      PIN_NUMBER='(2,0,0)';
      OUTPUT_TYPE='(TS,TS)';
      INPUT_LOAD='(-0.01,0.01)';
      OUTPUT_LOAD='(1.0,-1.0)';
    'RFU1':
      PIN_NUMBER='(144,0,0)';
      OUTPUT_TYPE='(TS,TS)';
      INPUT_LOAD='(-0.01,0.01)';
      OUTPUT_LOAD='(1.0,-1.0)';
    'RFU2':
      PIN_NUMBER='(149,0,0)';
      OUTPUT_TYPE='(TS,TS)';
      INPUT_LOAD='(-0.01,0.01)';
      OUTPUT_LOAD='(1.0,-1.0)';
    'RFU3':
      PIN_NUMBER='(150,0,0)';
      OUTPUT_TYPE='(TS,TS)';
      INPUT_LOAD='(-0.01,0.01)';
      OUTPUT_LOAD='(1.0,-1.0)';
    'RFU4':
      PIN_NUMBER='(220,0,0)';
      OUTPUT_TYPE='(TS,TS)';
      INPUT_LOAD='(-0.01,0.01)';
      OUTPUT_LOAD='(1.0,-1.0)';
    'RFU5':
      PIN_NUMBER='(231,0,0)';
      OUTPUT_TYPE='(TS,TS)';
      INPUT_LOAD='(-0.01,0.01)';
      OUTPUT_LOAD='(1.0,-1.0)';
    'RFU6':
      PIN_NUMBER='(232,0,0)';
      OUTPUT_TYPE='(TS,TS)';
      INPUT_LOAD='(-0.01,0.01)';
      OUTPUT_LOAD='(1.0,-1.0)';
    '-RESET':
      PIN_NUMBER='(207,0,0)';
      INPUT_LOAD='(-0.01,0.01)';
    '-PWR_GOOD||FAIL':
      PIN_NUMBER='(147,0,0)';
      BIDIRECTIONAL='TRUE';
      INPUT_LOAD='(-0.01,0.01)';
      OUTPUT_LOAD='(1.0,-1.0)';
    'PAR_B':
      PIN_NUMBER='(227,0,0)';
      INPUT_LOAD='(-0.01,0.01)';
    'PAR_A':
      PIN_NUMBER='(74,0,0)';
      INPUT_LOAD='(-0.01,0.01)';
    '-LBS||RSP_B':
      PIN_NUMBER='(87,0,0)';
      OUTPUT_LOAD='(1.0,-1.0)';
    '-LBD||RSP_A':
      PIN_NUMBER='(86,0,0)';
      OUTPUT_LOAD='(1.0,-1.0)';
    'HSDA':
      PIN_NUMBER='(5,0,0)';
      BIDIRECTIONAL='TRUE';
      INPUT_LOAD='(-0.01,0.01)';
      OUTPUT_LOAD='(1.0,-1.0)';
    'HSCL':
      PIN_NUMBER='(4,0,0)';
      INPUT_LOAD='(-0.01,0.01)';
    'HAS':
      PIN_NUMBER='(148,0,0)';
      INPUT_LOAD='(-0.01,0.01)';
    'DQ0_B':
      PIN_NUMBER='(100,0,0)';
      BIDIRECTIONAL='TRUE';
      INPUT_LOAD='(-0.01,0.01)';
      OUTPUT_LOAD='(1.0,-1.0)';
    'DQ1_B':
      PIN_NUMBER='(102,0,0)';
      BIDIRECTIONAL='TRUE';
      INPUT_LOAD='(-0.01,0.01)';
      OUTPUT_LOAD='(1.0,-1.0)';
    'DQ2_B':
      PIN_NUMBER='(245,0,0)';
      BIDIRECTIONAL='TRUE';
      INPUT_LOAD='(-0.01,0.01)';
      OUTPUT_LOAD='(1.0,-1.0)';
    'DQ3_B':
      PIN_NUMBER='(247,0,0)';
      BIDIRECTIONAL='TRUE';
      INPUT_LOAD='(-0.01,0.01)';
      OUTPUT_LOAD='(1.0,-1.0)';
    'DQ4_B':
      PIN_NUMBER='(107,0,0)';
      BIDIRECTIONAL='TRUE';
      INPUT_LOAD='(-0.01,0.01)';
      OUTPUT_LOAD='(1.0,-1.0)';
    'DQ5_B':
      PIN_NUMBER='(109,0,0)';
      BIDIRECTIONAL='TRUE';
      INPUT_LOAD='(-0.01,0.01)';
      OUTPUT_LOAD='(1.0,-1.0)';
    'DQ6_B':
      PIN_NUMBER='(252,0,0)';
      BIDIRECTIONAL='TRUE';
      INPUT_LOAD='(-0.01,0.01)';
      OUTPUT_LOAD='(1.0,-1.0)';
    'DQ7_B':
      PIN_NUMBER='(254,0,0)';
      BIDIRECTIONAL='TRUE';
      INPUT_LOAD='(-0.01,0.01)';
      OUTPUT_LOAD='(1.0,-1.0)';
    'DQ8_B':
      PIN_NUMBER='(111,0,0)';
      BIDIRECTIONAL='TRUE';
      INPUT_LOAD='(-0.01,0.01)';
      OUTPUT_LOAD='(1.0,-1.0)';
    'DQ9_B':
      PIN_NUMBER='(113,0,0)';
      BIDIRECTIONAL='TRUE';
      INPUT_LOAD='(-0.01,0.01)';
      OUTPUT_LOAD='(1.0,-1.0)';
    'DQ10_B':
      PIN_NUMBER='(256,0,0)';
      BIDIRECTIONAL='TRUE';
      INPUT_LOAD='(-0.01,0.01)';
      OUTPUT_LOAD='(1.0,-1.0)';
    'DQ11_B':
      PIN_NUMBER='(258,0,0)';
      BIDIRECTIONAL='TRUE';
      INPUT_LOAD='(-0.01,0.01)';
      OUTPUT_LOAD='(1.0,-1.0)';
    'DQ12_B':
      PIN_NUMBER='(118,0,0)';
      BIDIRECTIONAL='TRUE';
      INPUT_LOAD='(-0.01,0.01)';
      OUTPUT_LOAD='(1.0,-1.0)';
    'DQ13_B':
      PIN_NUMBER='(120,0,0)';
      BIDIRECTIONAL='TRUE';
      INPUT_LOAD='(-0.01,0.01)';
      OUTPUT_LOAD='(1.0,-1.0)';
    'DQ14_B':
      PIN_NUMBER='(263,0,0)';
      BIDIRECTIONAL='TRUE';
      INPUT_LOAD='(-0.01,0.01)';
      OUTPUT_LOAD='(1.0,-1.0)';
    'DQ15_B':
      PIN_NUMBER='(265,0,0)';
      BIDIRECTIONAL='TRUE';
      INPUT_LOAD='(-0.01,0.01)';
      OUTPUT_LOAD='(1.0,-1.0)';
    'DQ16_B':
      PIN_NUMBER='(122,0,0)';
      BIDIRECTIONAL='TRUE';
      INPUT_LOAD='(-0.01,0.01)';
      OUTPUT_LOAD='(1.0,-1.0)';
    'DQ17_B':
      PIN_NUMBER='(124,0,0)';
      BIDIRECTIONAL='TRUE';
      INPUT_LOAD='(-0.01,0.01)';
      OUTPUT_LOAD='(1.0,-1.0)';
    'DQ18_B':
      PIN_NUMBER='(267,0,0)';
      BIDIRECTIONAL='TRUE';
      INPUT_LOAD='(-0.01,0.01)';
      OUTPUT_LOAD='(1.0,-1.0)';
    'DQ19_B':
      PIN_NUMBER='(269,0,0)';
      BIDIRECTIONAL='TRUE';
      INPUT_LOAD='(-0.01,0.01)';
      OUTPUT_LOAD='(1.0,-1.0)';
    'DQ20_B':
      PIN_NUMBER='(129,0,0)';
      BIDIRECTIONAL='TRUE';
      INPUT_LOAD='(-0.01,0.01)';
      OUTPUT_LOAD='(1.0,-1.0)';
    'DQ21_B':
      PIN_NUMBER='(131,0,0)';
      BIDIRECTIONAL='TRUE';
      INPUT_LOAD='(-0.01,0.01)';
      OUTPUT_LOAD='(1.0,-1.0)';
    'DQ22_B':
      PIN_NUMBER='(274,0,0)';
      BIDIRECTIONAL='TRUE';
      INPUT_LOAD='(-0.01,0.01)';
      OUTPUT_LOAD='(1.0,-1.0)';
    'DQ23_B':
      PIN_NUMBER='(276,0,0)';
      BIDIRECTIONAL='TRUE';
      INPUT_LOAD='(-0.01,0.01)';
      OUTPUT_LOAD='(1.0,-1.0)';
    'DQ24_B':
      PIN_NUMBER='(133,0,0)';
      BIDIRECTIONAL='TRUE';
      INPUT_LOAD='(-0.01,0.01)';
      OUTPUT_LOAD='(1.0,-1.0)';
    'DQ25_B':
      PIN_NUMBER='(135,0,0)';
      BIDIRECTIONAL='TRUE';
      INPUT_LOAD='(-0.01,0.01)';
      OUTPUT_LOAD='(1.0,-1.0)';
    'DQ26_B':
      PIN_NUMBER='(278,0,0)';
      BIDIRECTIONAL='TRUE';
      INPUT_LOAD='(-0.01,0.01)';
      OUTPUT_LOAD='(1.0,-1.0)';
    'DQ27_B':
      PIN_NUMBER='(280,0,0)';
      BIDIRECTIONAL='TRUE';
      INPUT_LOAD='(-0.01,0.01)';
      OUTPUT_LOAD='(1.0,-1.0)';
    'DQ28_B':
      PIN_NUMBER='(140,0,0)';
      BIDIRECTIONAL='TRUE';
      INPUT_LOAD='(-0.01,0.01)';
      OUTPUT_LOAD='(1.0,-1.0)';
    'DQ29_B':
      PIN_NUMBER='(142,0,0)';
      BIDIRECTIONAL='TRUE';
      INPUT_LOAD='(-0.01,0.01)';
      OUTPUT_LOAD='(1.0,-1.0)';
    'DQ30_B':
      PIN_NUMBER='(285,0,0)';
      BIDIRECTIONAL='TRUE';
      INPUT_LOAD='(-0.01,0.01)';
      OUTPUT_LOAD='(1.0,-1.0)';
    'DQ31_B':
      PIN_NUMBER='(287,0,0)';
      BIDIRECTIONAL='TRUE';
      INPUT_LOAD='(-0.01,0.01)';
      OUTPUT_LOAD='(1.0,-1.0)';
    'DQ0_A':
      PIN_NUMBER='(7,0,0)';
      BIDIRECTIONAL='TRUE';
      INPUT_LOAD='(-0.01,0.01)';
      OUTPUT_LOAD='(1.0,-1.0)';
    'DQ1_A':
      PIN_NUMBER='(9,0,0)';
      BIDIRECTIONAL='TRUE';
      INPUT_LOAD='(-0.01,0.01)';
      OUTPUT_LOAD='(1.0,-1.0)';
    'DQ2_A':
      PIN_NUMBER='(152,0,0)';
      BIDIRECTIONAL='TRUE';
      INPUT_LOAD='(-0.01,0.01)';
      OUTPUT_LOAD='(1.0,-1.0)';
    'DQ3_A':
      PIN_NUMBER='(154,0,0)';
      BIDIRECTIONAL='TRUE';
      INPUT_LOAD='(-0.01,0.01)';
      OUTPUT_LOAD='(1.0,-1.0)';
    'DQ4_A':
      PIN_NUMBER='(14,0,0)';
      BIDIRECTIONAL='TRUE';
      INPUT_LOAD='(-0.01,0.01)';
      OUTPUT_LOAD='(1.0,-1.0)';
    'DQ5_A':
      PIN_NUMBER='(16,0,0)';
      BIDIRECTIONAL='TRUE';
      INPUT_LOAD='(-0.01,0.01)';
      OUTPUT_LOAD='(1.0,-1.0)';
    'DQ6_A':
      PIN_NUMBER='(159,0,0)';
      BIDIRECTIONAL='TRUE';
      INPUT_LOAD='(-0.01,0.01)';
      OUTPUT_LOAD='(1.0,-1.0)';
    'DQ7_A':
      PIN_NUMBER='(161,0,0)';
      BIDIRECTIONAL='TRUE';
      INPUT_LOAD='(-0.01,0.01)';
      OUTPUT_LOAD='(1.0,-1.0)';
    'DQ8_A':
      PIN_NUMBER='(18,0,0)';
      BIDIRECTIONAL='TRUE';
      INPUT_LOAD='(-0.01,0.01)';
      OUTPUT_LOAD='(1.0,-1.0)';
    'DQ9_A':
      PIN_NUMBER='(20,0,0)';
      BIDIRECTIONAL='TRUE';
      INPUT_LOAD='(-0.01,0.01)';
      OUTPUT_LOAD='(1.0,-1.0)';
    'DQ10_A':
      PIN_NUMBER='(163,0,0)';
      BIDIRECTIONAL='TRUE';
      INPUT_LOAD='(-0.01,0.01)';
      OUTPUT_LOAD='(1.0,-1.0)';
    'DQ11_A':
      PIN_NUMBER='(165,0,0)';
      BIDIRECTIONAL='TRUE';
      INPUT_LOAD='(-0.01,0.01)';
      OUTPUT_LOAD='(1.0,-1.0)';
    'DQ12_A':
      PIN_NUMBER='(25,0,0)';
      BIDIRECTIONAL='TRUE';
      INPUT_LOAD='(-0.01,0.01)';
      OUTPUT_LOAD='(1.0,-1.0)';
    'DQ13_A':
      PIN_NUMBER='(27,0,0)';
      BIDIRECTIONAL='TRUE';
      INPUT_LOAD='(-0.01,0.01)';
      OUTPUT_LOAD='(1.0,-1.0)';
    'DQ14_A':
      PIN_NUMBER='(170,0,0)';
      BIDIRECTIONAL='TRUE';
      INPUT_LOAD='(-0.01,0.01)';
      OUTPUT_LOAD='(1.0,-1.0)';
    'DQ15_A':
      PIN_NUMBER='(172,0,0)';
      BIDIRECTIONAL='TRUE';
      INPUT_LOAD='(-0.01,0.01)';
      OUTPUT_LOAD='(1.0,-1.0)';
    'DQ16_A':
      PIN_NUMBER='(29,0,0)';
      BIDIRECTIONAL='TRUE';
      INPUT_LOAD='(-0.01,0.01)';
      OUTPUT_LOAD='(1.0,-1.0)';
    'DQ17_A':
      PIN_NUMBER='(31,0,0)';
      BIDIRECTIONAL='TRUE';
      INPUT_LOAD='(-0.01,0.01)';
      OUTPUT_LOAD='(1.0,-1.0)';
    'DQ18_A':
      PIN_NUMBER='(174,0,0)';
      BIDIRECTIONAL='TRUE';
      INPUT_LOAD='(-0.01,0.01)';
      OUTPUT_LOAD='(1.0,-1.0)';
    'DQ19_A':
      PIN_NUMBER='(176,0,0)';
      BIDIRECTIONAL='TRUE';
      INPUT_LOAD='(-0.01,0.01)';
      OUTPUT_LOAD='(1.0,-1.0)';
    'DQ20_A':
      PIN_NUMBER='(36,0,0)';
      BIDIRECTIONAL='TRUE';
      INPUT_LOAD='(-0.01,0.01)';
      OUTPUT_LOAD='(1.0,-1.0)';
    'DQ21_A':
      PIN_NUMBER='(38,0,0)';
      BIDIRECTIONAL='TRUE';
      INPUT_LOAD='(-0.01,0.01)';
      OUTPUT_LOAD='(1.0,-1.0)';
    'DQ22_A':
      PIN_NUMBER='(181,0,0)';
      BIDIRECTIONAL='TRUE';
      INPUT_LOAD='(-0.01,0.01)';
      OUTPUT_LOAD='(1.0,-1.0)';
    'DQ23_A':
      PIN_NUMBER='(183,0,0)';
      BIDIRECTIONAL='TRUE';
      INPUT_LOAD='(-0.01,0.01)';
      OUTPUT_LOAD='(1.0,-1.0)';
    'DQ24_A':
      PIN_NUMBER='(40,0,0)';
      BIDIRECTIONAL='TRUE';
      INPUT_LOAD='(-0.01,0.01)';
      OUTPUT_LOAD='(1.0,-1.0)';
    'DQ25_A':
      PIN_NUMBER='(42,0,0)';
      BIDIRECTIONAL='TRUE';
      INPUT_LOAD='(-0.01,0.01)';
      OUTPUT_LOAD='(1.0,-1.0)';
    'DQ26_A':
      PIN_NUMBER='(185,0,0)';
      BIDIRECTIONAL='TRUE';
      INPUT_LOAD='(-0.01,0.01)';
      OUTPUT_LOAD='(1.0,-1.0)';
    'DQ27_A':
      PIN_NUMBER='(187,0,0)';
      BIDIRECTIONAL='TRUE';
      INPUT_LOAD='(-0.01,0.01)';
      OUTPUT_LOAD='(1.0,-1.0)';
    'DQ28_A':
      PIN_NUMBER='(47,0,0)';
      BIDIRECTIONAL='TRUE';
      INPUT_LOAD='(-0.01,0.01)';
      OUTPUT_LOAD='(1.0,-1.0)';
    'DQ29_A':
      PIN_NUMBER='(49,0,0)';
      BIDIRECTIONAL='TRUE';
      INPUT_LOAD='(-0.01,0.01)';
      OUTPUT_LOAD='(1.0,-1.0)';
    'DQ30_A':
      PIN_NUMBER='(192,0,0)';
      BIDIRECTIONAL='TRUE';
      INPUT_LOAD='(-0.01,0.01)';
      OUTPUT_LOAD='(1.0,-1.0)';
    '-CS1_B':
      PIN_NUMBER='(229,0,0)';
      INPUT_LOAD='(-0.01,0.01)';
    '-CS1_A':
      PIN_NUMBER='(209,0,0)';
      INPUT_LOAD='(-0.01,0.01)';
    '-CS0_B':
      PIN_NUMBER='(84,0,0)';
      INPUT_LOAD='(-0.01,0.01)';
    '-CS0_A':
      PIN_NUMBER='(64,0,0)';
      INPUT_LOAD='(-0.01,0.01)';
    'CK_T':
      PIN_NUMBER='(217,0,0)';
      INPUT_LOAD='(-0.01,0.01)';
    'CK_C':
      PIN_NUMBER='(218,0,0)';
      INPUT_LOAD='(-0.01,0.01)';
    'CB0_B':
      PIN_NUMBER='(96,0,0)';
      BIDIRECTIONAL='TRUE';
      INPUT_LOAD='(-0.01,0.01)';
      OUTPUT_LOAD='(1.0,-1.0)';
    'CB1_B':
      PIN_NUMBER='(98,0,0)';
      BIDIRECTIONAL='TRUE';
      INPUT_LOAD='(-0.01,0.01)';
      OUTPUT_LOAD='(1.0,-1.0)';
    'CB2_B':
      PIN_NUMBER='(241,0,0)';
      BIDIRECTIONAL='TRUE';
      INPUT_LOAD='(-0.01,0.01)';
      OUTPUT_LOAD='(1.0,-1.0)';
    'CB3_B':
      PIN_NUMBER='(243,0,0)';
      BIDIRECTIONAL='TRUE';
      INPUT_LOAD='(-0.01,0.01)';
      OUTPUT_LOAD='(1.0,-1.0)';
    'CB4_B':
      PIN_NUMBER='(89,0,0)';
      BIDIRECTIONAL='TRUE';
      INPUT_LOAD='(-0.01,0.01)';
      OUTPUT_LOAD='(1.0,-1.0)';
    'CB5_B':
      PIN_NUMBER='(91,0,0)';
      BIDIRECTIONAL='TRUE';
      INPUT_LOAD='(-0.01,0.01)';
      OUTPUT_LOAD='(1.0,-1.0)';
    'CB6_B':
      PIN_NUMBER='(234,0,0)';
      BIDIRECTIONAL='TRUE';
      INPUT_LOAD='(-0.01,0.01)';
      OUTPUT_LOAD='(1.0,-1.0)';
    'CB0_A':
      PIN_NUMBER='(51,0,0)';
      BIDIRECTIONAL='TRUE';
      INPUT_LOAD='(-0.01,0.01)';
      OUTPUT_LOAD='(1.0,-1.0)';
    'CB2_A':
      PIN_NUMBER='(196,0,0)';
      BIDIRECTIONAL='TRUE';
      INPUT_LOAD='(-0.01,0.01)';
      OUTPUT_LOAD='(1.0,-1.0)';
    'CB3_A':
      PIN_NUMBER='(198,0,0)';
      BIDIRECTIONAL='TRUE';
      INPUT_LOAD='(-0.01,0.01)';
      OUTPUT_LOAD='(1.0,-1.0)';
    'CB5_A':
      PIN_NUMBER='(60,0,0)';
      BIDIRECTIONAL='TRUE';
      INPUT_LOAD='(-0.01,0.01)';
      OUTPUT_LOAD='(1.0,-1.0)';
    'CB6_A':
      PIN_NUMBER='(203,0,0)';
      BIDIRECTIONAL='TRUE';
      INPUT_LOAD='(-0.01,0.01)';
      OUTPUT_LOAD='(1.0,-1.0)';
    'CA6_B':
      PIN_NUMBER='(82,0,0)';
      INPUT_LOAD='(-0.01,0.01)';
    'CA6_A':
      PIN_NUMBER='(72,0,0)';
      INPUT_LOAD='(-0.01,0.01)';
    'CA5_B':
      PIN_NUMBER='(225,0,0)';
      INPUT_LOAD='(-0.01,0.01)';
    'CA5_A':
      PIN_NUMBER='(215,0,0)';
      INPUT_LOAD='(-0.01,0.01)';
    'CA4_B':
      PIN_NUMBER='(80,0,0)';
      INPUT_LOAD='(-0.01,0.01)';
    'CA4_A':
      PIN_NUMBER='(70,0,0)';
      INPUT_LOAD='(-0.01,0.01)';
    'CA3_B':
      PIN_NUMBER='(223,0,0)';
      INPUT_LOAD='(-0.01,0.01)';
    'CA3_A':
      PIN_NUMBER='(213,0,0)';
      INPUT_LOAD='(-0.01,0.01)';
    'CA2_B':
      PIN_NUMBER='(78,0,0)';
      INPUT_LOAD='(-0.01,0.01)';
    'CA2_A':
      PIN_NUMBER='(68,0,0)';
      INPUT_LOAD='(-0.01,0.01)';
    'CA1_B':
      PIN_NUMBER='(221,0,0)';
      INPUT_LOAD='(-0.01,0.01)';
    'CA1_A':
      PIN_NUMBER='(211,0,0)';
      INPUT_LOAD='(-0.01,0.01)';
    'CA0_B':
      PIN_NUMBER='(76,0,0)';
      INPUT_LOAD='(-0.01,0.01)';
    'CA0_A':
      PIN_NUMBER='(66,0,0)';
      INPUT_LOAD='(-0.01,0.01)';
    '-ALERT':
      PIN_NUMBER='(62,0,0)';
      OUTPUT_LOAD='(1.0,-1.0)';
    'CB7_B':
      PIN_NUMBER='(236,0,0)';
      BIDIRECTIONAL='TRUE';
      INPUT_LOAD='(-0.01,0.01)';
      OUTPUT_LOAD='(1.0,-1.0)';
    'CB1_A':
      PIN_NUMBER='(53,0,0)';
      BIDIRECTIONAL='TRUE';
      INPUT_LOAD='(-0.01,0.01)';
      OUTPUT_LOAD='(1.0,-1.0)';
    'CB4_A':
      PIN_NUMBER='(58,0,0)';
      BIDIRECTIONAL='TRUE';
      INPUT_LOAD='(-0.01,0.01)';
      OUTPUT_LOAD='(1.0,-1.0)';
    'CB7_A':
      PIN_NUMBER='(205,0,0)';
      BIDIRECTIONAL='TRUE';
      INPUT_LOAD='(-0.01,0.01)';
      OUTPUT_LOAD='(1.0,-1.0)';
    'DQ31_A':
      PIN_NUMBER='(194,0,0)';
      BIDIRECTIONAL='TRUE';
      INPUT_LOAD='(-0.01,0.01)';
      OUTPUT_LOAD='(1.0,-1.0)';
    '-DQS9_B_T||TDQS9_B_T||DBI4_B':
      PIN_NUMBER='(0,93,0)';
      BIDIRECTIONAL='TRUE';
      INPUT_LOAD='(-0.01,0.01)';
      OUTPUT_LOAD='(1.0,-1.0)';
    'DQS9_B_C||TDQS9_B_C':
      PIN_NUMBER='(0,94,0)';
      BIDIRECTIONAL='TRUE';
      INPUT_LOAD='(-0.01,0.01)';
      OUTPUT_LOAD='(1.0,-1.0)';
    'DQS9_A_T||TDQS9_A_T':
      PIN_NUMBER='(0,201,0)';
      BIDIRECTIONAL='TRUE';
      INPUT_LOAD='(-0.01,0.01)';
      OUTPUT_LOAD='(1.0,-1.0)';
    'DQS9_A_C||TDQS9_A_C':
      PIN_NUMBER='(0,200,0)';
      BIDIRECTIONAL='TRUE';
      INPUT_LOAD='(-0.01,0.01)';
      OUTPUT_LOAD='(1.0,-1.0)';
    'DQS8_A_T||TDQS8_A_T':
      PIN_NUMBER='(0,190,0)';
      BIDIRECTIONAL='TRUE';
      INPUT_LOAD='(-0.01,0.01)';
      OUTPUT_LOAD='(1.0,-1.0)';
    'DQS8_A_C||TDQS8_A_C':
      PIN_NUMBER='(0,189,0)';
      BIDIRECTIONAL='TRUE';
      INPUT_LOAD='(-0.01,0.01)';
      OUTPUT_LOAD='(1.0,-1.0)';
    'DQS7_B_C||TDQS7_B_C':
      PIN_NUMBER='(0,271,0)';
      BIDIRECTIONAL='TRUE';
      INPUT_LOAD='(-0.01,0.01)';
      OUTPUT_LOAD='(1.0,-1.0)';
    'DQS7_A_T||TDQS7_A_T':
      PIN_NUMBER='(0,179,0)';
      BIDIRECTIONAL='TRUE';
      INPUT_LOAD='(-0.01,0.01)';
      OUTPUT_LOAD='(1.0,-1.0)';
    'DQS6_B_T||TDQS6_B_T':
      PIN_NUMBER='(0,261,0)';
      BIDIRECTIONAL='TRUE';
      INPUT_LOAD='(-0.01,0.01)';
      OUTPUT_LOAD='(1.0,-1.0)';
    'DQS6_B_C||TDQS6_B_C':
      PIN_NUMBER='(0,260,0)';
      BIDIRECTIONAL='TRUE';
      INPUT_LOAD='(-0.01,0.01)';
      OUTPUT_LOAD='(1.0,-1.0)';
    'DQS6_A_C||TDQS6_A_C||DQS6_A_T||TDQS6_A_T':
      PIN_NUMBER='(0,167,0)';
      BIDIRECTIONAL='TRUE';
      INPUT_LOAD='(-0.01,0.01)';
      OUTPUT_LOAD='(1.0,-1.0)';
    'DQS5_B_T||TDQS5_B_T':
      PIN_NUMBER='(0,250,0)';
      BIDIRECTIONAL='TRUE';
      INPUT_LOAD='(-0.01,0.01)';
      OUTPUT_LOAD='(1.0,-1.0)';
    'DQS5_B_C||TDQS5_B_C':
      PIN_NUMBER='(0,249,0)';
      BIDIRECTIONAL='TRUE';
      INPUT_LOAD='(-0.01,0.01)';
      OUTPUT_LOAD='(1.0,-1.0)';
    'DQS5_A_T||TDQS5_A_T':
      PIN_NUMBER='(0,157,0)';
      BIDIRECTIONAL='TRUE';
      INPUT_LOAD='(-0.01,0.01)';
      OUTPUT_LOAD='(1.0,-1.0)';
    'DQS5_A_C||TDQS5_A_C||DQS5_A_T||TDQS5_A_T':
      PIN_NUMBER='(0,156,0)';
      BIDIRECTIONAL='TRUE';
      INPUT_LOAD='(-0.01,0.01)';
      OUTPUT_LOAD='(1.0,-1.0)';
    'DQS4_B_T':
      PIN_NUMBER='(0,239,0)';
      BIDIRECTIONAL='TRUE';
      INPUT_LOAD='(-0.01,0.01)';
      OUTPUT_LOAD='(1.0,-1.0)';
    'DQS4_B_C':
      PIN_NUMBER='(0,238,0)';
      BIDIRECTIONAL='TRUE';
      INPUT_LOAD='(-0.01,0.01)';
      OUTPUT_LOAD='(1.0,-1.0)';
    'DQS4_A_T':
      PIN_NUMBER='(0,55,0)';
      BIDIRECTIONAL='TRUE';
      INPUT_LOAD='(-0.01,0.01)';
      OUTPUT_LOAD='(1.0,-1.0)';
    'DQS4_A_C':
      PIN_NUMBER='(0,56,0)';
      BIDIRECTIONAL='TRUE';
      INPUT_LOAD='(-0.01,0.01)';
      OUTPUT_LOAD='(1.0,-1.0)';
    'DQS3_B_T':
      PIN_NUMBER='(0,137,0)';
      BIDIRECTIONAL='TRUE';
      INPUT_LOAD='(-0.01,0.01)';
      OUTPUT_LOAD='(1.0,-1.0)';
    'DQS3_B_C':
      PIN_NUMBER='(0,138,0)';
      BIDIRECTIONAL='TRUE';
      INPUT_LOAD='(-0.01,0.01)';
      OUTPUT_LOAD='(1.0,-1.0)';
    'DQS3_A_T':
      PIN_NUMBER='(0,44,0)';
      BIDIRECTIONAL='TRUE';
      INPUT_LOAD='(-0.01,0.01)';
      OUTPUT_LOAD='(1.0,-1.0)';
    'DQS3_A_C':
      PIN_NUMBER='(0,45,0)';
      BIDIRECTIONAL='TRUE';
      INPUT_LOAD='(-0.01,0.01)';
      OUTPUT_LOAD='(1.0,-1.0)';
    'DQS2_B_T':
      PIN_NUMBER='(0,126,0)';
      BIDIRECTIONAL='TRUE';
      INPUT_LOAD='(-0.01,0.01)';
      OUTPUT_LOAD='(1.0,-1.0)';
    'DQS2_B_C':
      PIN_NUMBER='(0,127,0)';
      BIDIRECTIONAL='TRUE';
      INPUT_LOAD='(-0.01,0.01)';
      OUTPUT_LOAD='(1.0,-1.0)';
    'DQS2_A_T':
      PIN_NUMBER='(0,33,0)';
      BIDIRECTIONAL='TRUE';
      INPUT_LOAD='(-0.01,0.01)';
      OUTPUT_LOAD='(1.0,-1.0)';
    'DQS2_A_C':
      PIN_NUMBER='(0,34,0)';
      BIDIRECTIONAL='TRUE';
      INPUT_LOAD='(-0.01,0.01)';
      OUTPUT_LOAD='(1.0,-1.0)';
    'DQS1_B_T':
      PIN_NUMBER='(0,115,0)';
      BIDIRECTIONAL='TRUE';
      INPUT_LOAD='(-0.01,0.01)';
      OUTPUT_LOAD='(1.0,-1.0)';
    'DQS1_B_C':
      PIN_NUMBER='(0,116,0)';
      BIDIRECTIONAL='TRUE';
      INPUT_LOAD='(-0.01,0.01)';
      OUTPUT_LOAD='(1.0,-1.0)';
    'DQS1_A_T':
      PIN_NUMBER='(0,22,0)';
      BIDIRECTIONAL='TRUE';
      INPUT_LOAD='(-0.01,0.01)';
      OUTPUT_LOAD='(1.0,-1.0)';
    'DQS1_A_C':
      PIN_NUMBER='(0,23,0)';
      BIDIRECTIONAL='TRUE';
      INPUT_LOAD='(-0.01,0.01)';
      OUTPUT_LOAD='(1.0,-1.0)';
    'DQS0_B_T':
      PIN_NUMBER='(0,104,0)';
      BIDIRECTIONAL='TRUE';
      INPUT_LOAD='(-0.01,0.01)';
      OUTPUT_LOAD='(1.0,-1.0)';
    'DQS0_B_C':
      PIN_NUMBER='(0,105,0)';
      BIDIRECTIONAL='TRUE';
      INPUT_LOAD='(-0.01,0.01)';
      OUTPUT_LOAD='(1.0,-1.0)';
    'DQS0_A_T':
      PIN_NUMBER='(0,11,0)';
      BIDIRECTIONAL='TRUE';
      INPUT_LOAD='(-0.01,0.01)';
      OUTPUT_LOAD='(1.0,-1.0)';
    'DQS0_A_C':
      PIN_NUMBER='(0,12,0)';
      BIDIRECTIONAL='TRUE';
      INPUT_LOAD='(-0.01,0.01)';
      OUTPUT_LOAD='(1.0,-1.0)';
    'DQS7_B_T||TDQS7_B_T':
      PIN_NUMBER='(0,272,0)';
      BIDIRECTIONAL='TRUE';
      INPUT_LOAD='(-0.01,0.01)';
      OUTPUT_LOAD='(1.0,-1.0)';
    'DQS8_B_C||TDQS8_B_C':
      PIN_NUMBER='(0,282,0)';
      BIDIRECTIONAL='TRUE';
      INPUT_LOAD='(-0.01,0.01)';
      OUTPUT_LOAD='(1.0,-1.0)';
    'DQS8_B_T||TDQS8_B_T':
      PIN_NUMBER='(0,283,0)';
      BIDIRECTIONAL='TRUE';
      INPUT_LOAD='(-0.01,0.01)';
      OUTPUT_LOAD='(1.0,-1.0)';
    'DQS6_A_T||TDQS6_A_T':
      PIN_NUMBER='(0,168,0)';
      BIDIRECTIONAL='TRUE';
      INPUT_LOAD='(-0.01,0.01)';
      OUTPUT_LOAD='(1.0,-1.0)';
    'DQS7_A_C||TDQS7_A_C':
      PIN_NUMBER='(0,178,0)';
      BIDIRECTIONAL='TRUE';
      INPUT_LOAD='(-0.01,0.01)';
      OUTPUT_LOAD='(1.0,-1.0)';
    'VSS0':
      PIN_NUMBER='(0,0,6)';
      PINUSE='POWER';
      NO_LOAD_CHECK='Both';
      NO_IO_CHECK='Both';
      NO_ASSERT_CHECK='TRUE';
      NO_DIR_CHECK='TRUE';
      ALLOW_CONNECT='TRUE';
    'VSS1':
      PIN_NUMBER='(0,0,8)';
      PINUSE='POWER';
      NO_LOAD_CHECK='Both';
      NO_IO_CHECK='Both';
      NO_ASSERT_CHECK='TRUE';
      NO_DIR_CHECK='TRUE';
      ALLOW_CONNECT='TRUE';
    'VSS2':
      PIN_NUMBER='(0,0,10)';
      PINUSE='POWER';
      NO_LOAD_CHECK='Both';
      NO_IO_CHECK='Both';
      NO_ASSERT_CHECK='TRUE';
      NO_DIR_CHECK='TRUE';
      ALLOW_CONNECT='TRUE';
    'VSS3':
      PIN_NUMBER='(0,0,13)';
      PINUSE='POWER';
      NO_LOAD_CHECK='Both';
      NO_IO_CHECK='Both';
      NO_ASSERT_CHECK='TRUE';
      NO_DIR_CHECK='TRUE';
      ALLOW_CONNECT='TRUE';
    'VSS4':
      PIN_NUMBER='(0,0,15)';
      PINUSE='POWER';
      NO_LOAD_CHECK='Both';
      NO_IO_CHECK='Both';
      NO_ASSERT_CHECK='TRUE';
      NO_DIR_CHECK='TRUE';
      ALLOW_CONNECT='TRUE';
    'VSS5':
      PIN_NUMBER='(0,0,17)';
      PINUSE='POWER';
      NO_LOAD_CHECK='Both';
      NO_IO_CHECK='Both';
      NO_ASSERT_CHECK='TRUE';
      NO_DIR_CHECK='TRUE';
      ALLOW_CONNECT='TRUE';
    'VSS6':
      PIN_NUMBER='(0,0,19)';
      PINUSE='POWER';
      NO_LOAD_CHECK='Both';
      NO_IO_CHECK='Both';
      NO_ASSERT_CHECK='TRUE';
      NO_DIR_CHECK='TRUE';
      ALLOW_CONNECT='TRUE';
    'VSS7':
      PIN_NUMBER='(0,0,21)';
      PINUSE='POWER';
      NO_LOAD_CHECK='Both';
      NO_IO_CHECK='Both';
      NO_ASSERT_CHECK='TRUE';
      NO_DIR_CHECK='TRUE';
      ALLOW_CONNECT='TRUE';
    'VSS8':
      PIN_NUMBER='(0,0,24)';
      PINUSE='POWER';
      NO_LOAD_CHECK='Both';
      NO_IO_CHECK='Both';
      NO_ASSERT_CHECK='TRUE';
      NO_DIR_CHECK='TRUE';
      ALLOW_CONNECT='TRUE';
    'VSS9':
      PIN_NUMBER='(0,0,26)';
      PINUSE='POWER';
      NO_LOAD_CHECK='Both';
      NO_IO_CHECK='Both';
      NO_ASSERT_CHECK='TRUE';
      NO_DIR_CHECK='TRUE';
      ALLOW_CONNECT='TRUE';
    'VSS10':
      PIN_NUMBER='(0,0,28)';
      PINUSE='POWER';
      NO_LOAD_CHECK='Both';
      NO_IO_CHECK='Both';
      NO_ASSERT_CHECK='TRUE';
      NO_DIR_CHECK='TRUE';
      ALLOW_CONNECT='TRUE';
    'VSS11':
      PIN_NUMBER='(0,0,30)';
      PINUSE='POWER';
      NO_LOAD_CHECK='Both';
      NO_IO_CHECK='Both';
      NO_ASSERT_CHECK='TRUE';
      NO_DIR_CHECK='TRUE';
      ALLOW_CONNECT='TRUE';
    'VSS12':
      PIN_NUMBER='(0,0,32)';
      PINUSE='POWER';
      NO_LOAD_CHECK='Both';
      NO_IO_CHECK='Both';
      NO_ASSERT_CHECK='TRUE';
      NO_DIR_CHECK='TRUE';
      ALLOW_CONNECT='TRUE';
    'VSS13':
      PIN_NUMBER='(0,0,35)';
      PINUSE='POWER';
      NO_LOAD_CHECK='Both';
      NO_IO_CHECK='Both';
      NO_ASSERT_CHECK='TRUE';
      NO_DIR_CHECK='TRUE';
      ALLOW_CONNECT='TRUE';
    'VSS14':
      PIN_NUMBER='(0,0,37)';
      PINUSE='POWER';
      NO_LOAD_CHECK='Both';
      NO_IO_CHECK='Both';
      NO_ASSERT_CHECK='TRUE';
      NO_DIR_CHECK='TRUE';
      ALLOW_CONNECT='TRUE';
    'VSS15':
      PIN_NUMBER='(0,0,39)';
      PINUSE='POWER';
      NO_LOAD_CHECK='Both';
      NO_IO_CHECK='Both';
      NO_ASSERT_CHECK='TRUE';
      NO_DIR_CHECK='TRUE';
      ALLOW_CONNECT='TRUE';
    'VSS16':
      PIN_NUMBER='(0,0,41)';
      PINUSE='POWER';
      NO_LOAD_CHECK='Both';
      NO_IO_CHECK='Both';
      NO_ASSERT_CHECK='TRUE';
      NO_DIR_CHECK='TRUE';
      ALLOW_CONNECT='TRUE';
    'VSS17':
      PIN_NUMBER='(0,0,43)';
      PINUSE='POWER';
      NO_LOAD_CHECK='Both';
      NO_IO_CHECK='Both';
      NO_ASSERT_CHECK='TRUE';
      NO_DIR_CHECK='TRUE';
      ALLOW_CONNECT='TRUE';
    'VSS18':
      PIN_NUMBER='(0,0,46)';
      PINUSE='POWER';
      NO_LOAD_CHECK='Both';
      NO_IO_CHECK='Both';
      NO_ASSERT_CHECK='TRUE';
      NO_DIR_CHECK='TRUE';
      ALLOW_CONNECT='TRUE';
    'VSS19':
      PIN_NUMBER='(0,0,48)';
      PINUSE='POWER';
      NO_LOAD_CHECK='Both';
      NO_IO_CHECK='Both';
      NO_ASSERT_CHECK='TRUE';
      NO_DIR_CHECK='TRUE';
      ALLOW_CONNECT='TRUE';
    'VSS20':
      PIN_NUMBER='(0,0,50)';
      PINUSE='POWER';
      NO_LOAD_CHECK='Both';
      NO_IO_CHECK='Both';
      NO_ASSERT_CHECK='TRUE';
      NO_DIR_CHECK='TRUE';
      ALLOW_CONNECT='TRUE';
    'VSS21':
      PIN_NUMBER='(0,0,52)';
      PINUSE='POWER';
      NO_LOAD_CHECK='Both';
      NO_IO_CHECK='Both';
      NO_ASSERT_CHECK='TRUE';
      NO_DIR_CHECK='TRUE';
      ALLOW_CONNECT='TRUE';
    'VSS22':
      PIN_NUMBER='(0,0,54)';
      PINUSE='POWER';
      NO_LOAD_CHECK='Both';
      NO_IO_CHECK='Both';
      NO_ASSERT_CHECK='TRUE';
      NO_DIR_CHECK='TRUE';
      ALLOW_CONNECT='TRUE';
    'VSS23':
      PIN_NUMBER='(0,0,57)';
      PINUSE='POWER';
      NO_LOAD_CHECK='Both';
      NO_IO_CHECK='Both';
      NO_ASSERT_CHECK='TRUE';
      NO_DIR_CHECK='TRUE';
      ALLOW_CONNECT='TRUE';
    'VSS24':
      PIN_NUMBER='(0,0,59)';
      PINUSE='POWER';
      NO_LOAD_CHECK='Both';
      NO_IO_CHECK='Both';
      NO_ASSERT_CHECK='TRUE';
      NO_DIR_CHECK='TRUE';
      ALLOW_CONNECT='TRUE';
    'VSS25':
      PIN_NUMBER='(0,0,61)';
      PINUSE='POWER';
      NO_LOAD_CHECK='Both';
      NO_IO_CHECK='Both';
      NO_ASSERT_CHECK='TRUE';
      NO_DIR_CHECK='TRUE';
      ALLOW_CONNECT='TRUE';
    'VSS26':
      PIN_NUMBER='(0,0,63)';
      PINUSE='POWER';
      NO_LOAD_CHECK='Both';
      NO_IO_CHECK='Both';
      NO_ASSERT_CHECK='TRUE';
      NO_DIR_CHECK='TRUE';
      ALLOW_CONNECT='TRUE';
    'VSS27':
      PIN_NUMBER='(0,0,65)';
      PINUSE='POWER';
      NO_LOAD_CHECK='Both';
      NO_IO_CHECK='Both';
      NO_ASSERT_CHECK='TRUE';
      NO_DIR_CHECK='TRUE';
      ALLOW_CONNECT='TRUE';
    'VSS28':
      PIN_NUMBER='(0,0,67)';
      PINUSE='POWER';
      NO_LOAD_CHECK='Both';
      NO_IO_CHECK='Both';
      NO_ASSERT_CHECK='TRUE';
      NO_DIR_CHECK='TRUE';
      ALLOW_CONNECT='TRUE';
    'VSS29':
      PIN_NUMBER='(0,0,69)';
      PINUSE='POWER';
      NO_LOAD_CHECK='Both';
      NO_IO_CHECK='Both';
      NO_ASSERT_CHECK='TRUE';
      NO_DIR_CHECK='TRUE';
      ALLOW_CONNECT='TRUE';
    'VSS30':
      PIN_NUMBER='(0,0,71)';
      PINUSE='POWER';
      NO_LOAD_CHECK='Both';
      NO_IO_CHECK='Both';
      NO_ASSERT_CHECK='TRUE';
      NO_DIR_CHECK='TRUE';
      ALLOW_CONNECT='TRUE';
    'VSS31':
      PIN_NUMBER='(0,0,73)';
      PINUSE='POWER';
      NO_LOAD_CHECK='Both';
      NO_IO_CHECK='Both';
      NO_ASSERT_CHECK='TRUE';
      NO_DIR_CHECK='TRUE';
      ALLOW_CONNECT='TRUE';
    'VSS32':
      PIN_NUMBER='(0,0,75)';
      PINUSE='POWER';
      NO_LOAD_CHECK='Both';
      NO_IO_CHECK='Both';
      NO_ASSERT_CHECK='TRUE';
      NO_DIR_CHECK='TRUE';
      ALLOW_CONNECT='TRUE';
    'VSS33':
      PIN_NUMBER='(0,0,77)';
      PINUSE='POWER';
      NO_LOAD_CHECK='Both';
      NO_IO_CHECK='Both';
      NO_ASSERT_CHECK='TRUE';
      NO_DIR_CHECK='TRUE';
      ALLOW_CONNECT='TRUE';
    'VSS34':
      PIN_NUMBER='(0,0,79)';
      PINUSE='POWER';
      NO_LOAD_CHECK='Both';
      NO_IO_CHECK='Both';
      NO_ASSERT_CHECK='TRUE';
      NO_DIR_CHECK='TRUE';
      ALLOW_CONNECT='TRUE';
    'VSS35':
      PIN_NUMBER='(0,0,81)';
      PINUSE='POWER';
      NO_LOAD_CHECK='Both';
      NO_IO_CHECK='Both';
      NO_ASSERT_CHECK='TRUE';
      NO_DIR_CHECK='TRUE';
      ALLOW_CONNECT='TRUE';
    'VSS36':
      PIN_NUMBER='(0,0,83)';
      PINUSE='POWER';
      NO_LOAD_CHECK='Both';
      NO_IO_CHECK='Both';
      NO_ASSERT_CHECK='TRUE';
      NO_DIR_CHECK='TRUE';
      ALLOW_CONNECT='TRUE';
    'VSS37':
      PIN_NUMBER='(0,0,85)';
      PINUSE='POWER';
      NO_LOAD_CHECK='Both';
      NO_IO_CHECK='Both';
      NO_ASSERT_CHECK='TRUE';
      NO_DIR_CHECK='TRUE';
      ALLOW_CONNECT='TRUE';
    'VSS38':
      PIN_NUMBER='(0,0,88)';
      PINUSE='POWER';
      NO_LOAD_CHECK='Both';
      NO_IO_CHECK='Both';
      NO_ASSERT_CHECK='TRUE';
      NO_DIR_CHECK='TRUE';
      ALLOW_CONNECT='TRUE';
    'VSS39':
      PIN_NUMBER='(0,0,90)';
      PINUSE='POWER';
      NO_LOAD_CHECK='Both';
      NO_IO_CHECK='Both';
      NO_ASSERT_CHECK='TRUE';
      NO_DIR_CHECK='TRUE';
      ALLOW_CONNECT='TRUE';
    'VSS40':
      PIN_NUMBER='(0,0,92)';
      PINUSE='POWER';
      NO_LOAD_CHECK='Both';
      NO_IO_CHECK='Both';
      NO_ASSERT_CHECK='TRUE';
      NO_DIR_CHECK='TRUE';
      ALLOW_CONNECT='TRUE';
    'VSS41':
      PIN_NUMBER='(0,0,95)';
      PINUSE='POWER';
      NO_LOAD_CHECK='Both';
      NO_IO_CHECK='Both';
      NO_ASSERT_CHECK='TRUE';
      NO_DIR_CHECK='TRUE';
      ALLOW_CONNECT='TRUE';
    'VSS42':
      PIN_NUMBER='(0,0,97)';
      PINUSE='POWER';
      NO_LOAD_CHECK='Both';
      NO_IO_CHECK='Both';
      NO_ASSERT_CHECK='TRUE';
      NO_DIR_CHECK='TRUE';
      ALLOW_CONNECT='TRUE';
    'VSS43':
      PIN_NUMBER='(0,0,99)';
      PINUSE='POWER';
      NO_LOAD_CHECK='Both';
      NO_IO_CHECK='Both';
      NO_ASSERT_CHECK='TRUE';
      NO_DIR_CHECK='TRUE';
      ALLOW_CONNECT='TRUE';
    'VSS44':
      PIN_NUMBER='(0,0,101)';
      PINUSE='POWER';
      NO_LOAD_CHECK='Both';
      NO_IO_CHECK='Both';
      NO_ASSERT_CHECK='TRUE';
      NO_DIR_CHECK='TRUE';
      ALLOW_CONNECT='TRUE';
    'VSS45':
      PIN_NUMBER='(0,0,103)';
      PINUSE='POWER';
      NO_LOAD_CHECK='Both';
      NO_IO_CHECK='Both';
      NO_ASSERT_CHECK='TRUE';
      NO_DIR_CHECK='TRUE';
      ALLOW_CONNECT='TRUE';
    'VSS46':
      PIN_NUMBER='(0,0,106)';
      PINUSE='POWER';
      NO_LOAD_CHECK='Both';
      NO_IO_CHECK='Both';
      NO_ASSERT_CHECK='TRUE';
      NO_DIR_CHECK='TRUE';
      ALLOW_CONNECT='TRUE';
    'VSS47':
      PIN_NUMBER='(0,0,108)';
      PINUSE='POWER';
      NO_LOAD_CHECK='Both';
      NO_IO_CHECK='Both';
      NO_ASSERT_CHECK='TRUE';
      NO_DIR_CHECK='TRUE';
      ALLOW_CONNECT='TRUE';
    'VSS48':
      PIN_NUMBER='(0,0,110)';
      PINUSE='POWER';
      NO_LOAD_CHECK='Both';
      NO_IO_CHECK='Both';
      NO_ASSERT_CHECK='TRUE';
      NO_DIR_CHECK='TRUE';
      ALLOW_CONNECT='TRUE';
    'VSS49':
      PIN_NUMBER='(0,0,112)';
      PINUSE='POWER';
      NO_LOAD_CHECK='Both';
      NO_IO_CHECK='Both';
      NO_ASSERT_CHECK='TRUE';
      NO_DIR_CHECK='TRUE';
      ALLOW_CONNECT='TRUE';
    'VSS50':
      PIN_NUMBER='(0,0,114)';
      PINUSE='POWER';
      NO_LOAD_CHECK='Both';
      NO_IO_CHECK='Both';
      NO_ASSERT_CHECK='TRUE';
      NO_DIR_CHECK='TRUE';
      ALLOW_CONNECT='TRUE';
    'VSS51':
      PIN_NUMBER='(0,0,117)';
      PINUSE='POWER';
      NO_LOAD_CHECK='Both';
      NO_IO_CHECK='Both';
      NO_ASSERT_CHECK='TRUE';
      NO_DIR_CHECK='TRUE';
      ALLOW_CONNECT='TRUE';
    'VSS52':
      PIN_NUMBER='(0,0,119)';
      PINUSE='POWER';
      NO_LOAD_CHECK='Both';
      NO_IO_CHECK='Both';
      NO_ASSERT_CHECK='TRUE';
      NO_DIR_CHECK='TRUE';
      ALLOW_CONNECT='TRUE';
    'VSS53':
      PIN_NUMBER='(0,0,121)';
      PINUSE='POWER';
      NO_LOAD_CHECK='Both';
      NO_IO_CHECK='Both';
      NO_ASSERT_CHECK='TRUE';
      NO_DIR_CHECK='TRUE';
      ALLOW_CONNECT='TRUE';
    'VSS54':
      PIN_NUMBER='(0,0,123)';
      PINUSE='POWER';
      NO_LOAD_CHECK='Both';
      NO_IO_CHECK='Both';
      NO_ASSERT_CHECK='TRUE';
      NO_DIR_CHECK='TRUE';
      ALLOW_CONNECT='TRUE';
    'VSS55':
      PIN_NUMBER='(0,0,125)';
      PINUSE='POWER';
      NO_LOAD_CHECK='Both';
      NO_IO_CHECK='Both';
      NO_ASSERT_CHECK='TRUE';
      NO_DIR_CHECK='TRUE';
      ALLOW_CONNECT='TRUE';
    'VSS56':
      PIN_NUMBER='(0,0,128)';
      PINUSE='POWER';
      NO_LOAD_CHECK='Both';
      NO_IO_CHECK='Both';
      NO_ASSERT_CHECK='TRUE';
      NO_DIR_CHECK='TRUE';
      ALLOW_CONNECT='TRUE';
    'VSS57':
      PIN_NUMBER='(0,0,130)';
      PINUSE='POWER';
      NO_LOAD_CHECK='Both';
      NO_IO_CHECK='Both';
      NO_ASSERT_CHECK='TRUE';
      NO_DIR_CHECK='TRUE';
      ALLOW_CONNECT='TRUE';
    'VSS59':
      PIN_NUMBER='(0,0,134)';
      PINUSE='POWER';
      NO_LOAD_CHECK='Both';
      NO_IO_CHECK='Both';
      NO_ASSERT_CHECK='TRUE';
      NO_DIR_CHECK='TRUE';
      ALLOW_CONNECT='TRUE';
    'VSS63':
      PIN_NUMBER='(0,0,143)';
      PINUSE='POWER';
      NO_LOAD_CHECK='Both';
      NO_IO_CHECK='Both';
      NO_ASSERT_CHECK='TRUE';
      NO_DIR_CHECK='TRUE';
      ALLOW_CONNECT='TRUE';
    'VSS64':
      PIN_NUMBER='(0,0,151)';
      PINUSE='POWER';
      NO_LOAD_CHECK='Both';
      NO_IO_CHECK='Both';
      NO_ASSERT_CHECK='TRUE';
      NO_DIR_CHECK='TRUE';
      ALLOW_CONNECT='TRUE';
    'VSS65':
      PIN_NUMBER='(0,0,153)';
      PINUSE='POWER';
      NO_LOAD_CHECK='Both';
      NO_IO_CHECK='Both';
      NO_ASSERT_CHECK='TRUE';
      NO_DIR_CHECK='TRUE';
      ALLOW_CONNECT='TRUE';
    'VSS66':
      PIN_NUMBER='(0,0,155)';
      PINUSE='POWER';
      NO_LOAD_CHECK='Both';
      NO_IO_CHECK='Both';
      NO_ASSERT_CHECK='TRUE';
      NO_DIR_CHECK='TRUE';
      ALLOW_CONNECT='TRUE';
    'VSS67':
      PIN_NUMBER='(0,0,158)';
      PINUSE='POWER';
      NO_LOAD_CHECK='Both';
      NO_IO_CHECK='Both';
      NO_ASSERT_CHECK='TRUE';
      NO_DIR_CHECK='TRUE';
      ALLOW_CONNECT='TRUE';
    'VSS68':
      PIN_NUMBER='(0,0,160)';
      PINUSE='POWER';
      NO_LOAD_CHECK='Both';
      NO_IO_CHECK='Both';
      NO_ASSERT_CHECK='TRUE';
      NO_DIR_CHECK='TRUE';
      ALLOW_CONNECT='TRUE';
    'VSS69':
      PIN_NUMBER='(0,0,162)';
      PINUSE='POWER';
      NO_LOAD_CHECK='Both';
      NO_IO_CHECK='Both';
      NO_ASSERT_CHECK='TRUE';
      NO_DIR_CHECK='TRUE';
      ALLOW_CONNECT='TRUE';
    'VSS70':
      PIN_NUMBER='(0,0,164)';
      PINUSE='POWER';
      NO_LOAD_CHECK='Both';
      NO_IO_CHECK='Both';
      NO_ASSERT_CHECK='TRUE';
      NO_DIR_CHECK='TRUE';
      ALLOW_CONNECT='TRUE';
    'VSS71':
      PIN_NUMBER='(0,0,166)';
      PINUSE='POWER';
      NO_LOAD_CHECK='Both';
      NO_IO_CHECK='Both';
      NO_ASSERT_CHECK='TRUE';
      NO_DIR_CHECK='TRUE';
      ALLOW_CONNECT='TRUE';
    'VSS72':
      PIN_NUMBER='(0,0,169)';
      PINUSE='POWER';
      NO_LOAD_CHECK='Both';
      NO_IO_CHECK='Both';
      NO_ASSERT_CHECK='TRUE';
      NO_DIR_CHECK='TRUE';
      ALLOW_CONNECT='TRUE';
    'VSS73':
      PIN_NUMBER='(0,0,171)';
      PINUSE='POWER';
      NO_LOAD_CHECK='Both';
      NO_IO_CHECK='Both';
      NO_ASSERT_CHECK='TRUE';
      NO_DIR_CHECK='TRUE';
      ALLOW_CONNECT='TRUE';
    'VSS74':
      PIN_NUMBER='(0,0,173)';
      PINUSE='POWER';
      NO_LOAD_CHECK='Both';
      NO_IO_CHECK='Both';
      NO_ASSERT_CHECK='TRUE';
      NO_DIR_CHECK='TRUE';
      ALLOW_CONNECT='TRUE';
    'VSS75':
      PIN_NUMBER='(0,0,175)';
      PINUSE='POWER';
      NO_LOAD_CHECK='Both';
      NO_IO_CHECK='Both';
      NO_ASSERT_CHECK='TRUE';
      NO_DIR_CHECK='TRUE';
      ALLOW_CONNECT='TRUE';
    'VSS76':
      PIN_NUMBER='(0,0,177)';
      PINUSE='POWER';
      NO_LOAD_CHECK='Both';
      NO_IO_CHECK='Both';
      NO_ASSERT_CHECK='TRUE';
      NO_DIR_CHECK='TRUE';
      ALLOW_CONNECT='TRUE';
    'VSS77':
      PIN_NUMBER='(0,0,180)';
      PINUSE='POWER';
      NO_LOAD_CHECK='Both';
      NO_IO_CHECK='Both';
      NO_ASSERT_CHECK='TRUE';
      NO_DIR_CHECK='TRUE';
      ALLOW_CONNECT='TRUE';
    'VSS78':
      PIN_NUMBER='(0,0,182)';
      PINUSE='POWER';
      NO_LOAD_CHECK='Both';
      NO_IO_CHECK='Both';
      NO_ASSERT_CHECK='TRUE';
      NO_DIR_CHECK='TRUE';
      ALLOW_CONNECT='TRUE';
    'VSS79':
      PIN_NUMBER='(0,0,184)';
      PINUSE='POWER';
      NO_LOAD_CHECK='Both';
      NO_IO_CHECK='Both';
      NO_ASSERT_CHECK='TRUE';
      NO_DIR_CHECK='TRUE';
      ALLOW_CONNECT='TRUE';
    'VSS80':
      PIN_NUMBER='(0,0,186)';
      PINUSE='POWER';
      NO_LOAD_CHECK='Both';
      NO_IO_CHECK='Both';
      NO_ASSERT_CHECK='TRUE';
      NO_DIR_CHECK='TRUE';
      ALLOW_CONNECT='TRUE';
    'VSS81':
      PIN_NUMBER='(0,0,188)';
      PINUSE='POWER';
      NO_LOAD_CHECK='Both';
      NO_IO_CHECK='Both';
      NO_ASSERT_CHECK='TRUE';
      NO_DIR_CHECK='TRUE';
      ALLOW_CONNECT='TRUE';
    'VSS82':
      PIN_NUMBER='(0,0,191)';
      PINUSE='POWER';
      NO_LOAD_CHECK='Both';
      NO_IO_CHECK='Both';
      NO_ASSERT_CHECK='TRUE';
      NO_DIR_CHECK='TRUE';
      ALLOW_CONNECT='TRUE';
    'VSS83':
      PIN_NUMBER='(0,0,193)';
      PINUSE='POWER';
      NO_LOAD_CHECK='Both';
      NO_IO_CHECK='Both';
      NO_ASSERT_CHECK='TRUE';
      NO_DIR_CHECK='TRUE';
      ALLOW_CONNECT='TRUE';
    'VSS84':
      PIN_NUMBER='(0,0,195)';
      PINUSE='POWER';
      NO_LOAD_CHECK='Both';
      NO_IO_CHECK='Both';
      NO_ASSERT_CHECK='TRUE';
      NO_DIR_CHECK='TRUE';
      ALLOW_CONNECT='TRUE';
    'VSS85':
      PIN_NUMBER='(0,0,197)';
      PINUSE='POWER';
      NO_LOAD_CHECK='Both';
      NO_IO_CHECK='Both';
      NO_ASSERT_CHECK='TRUE';
      NO_DIR_CHECK='TRUE';
      ALLOW_CONNECT='TRUE';
    'VSS86':
      PIN_NUMBER='(0,0,199)';
      PINUSE='POWER';
      NO_LOAD_CHECK='Both';
      NO_IO_CHECK='Both';
      NO_ASSERT_CHECK='TRUE';
      NO_DIR_CHECK='TRUE';
      ALLOW_CONNECT='TRUE';
    'VSS87':
      PIN_NUMBER='(0,0,202)';
      PINUSE='POWER';
      NO_LOAD_CHECK='Both';
      NO_IO_CHECK='Both';
      NO_ASSERT_CHECK='TRUE';
      NO_DIR_CHECK='TRUE';
      ALLOW_CONNECT='TRUE';
    'VSS88':
      PIN_NUMBER='(0,0,204)';
      PINUSE='POWER';
      NO_LOAD_CHECK='Both';
      NO_IO_CHECK='Both';
      NO_ASSERT_CHECK='TRUE';
      NO_DIR_CHECK='TRUE';
      ALLOW_CONNECT='TRUE';
    'VSS89':
      PIN_NUMBER='(0,0,206)';
      PINUSE='POWER';
      NO_LOAD_CHECK='Both';
      NO_IO_CHECK='Both';
      NO_ASSERT_CHECK='TRUE';
      NO_DIR_CHECK='TRUE';
      ALLOW_CONNECT='TRUE';
    'VSS90':
      PIN_NUMBER='(0,0,208)';
      PINUSE='POWER';
      NO_LOAD_CHECK='Both';
      NO_IO_CHECK='Both';
      NO_ASSERT_CHECK='TRUE';
      NO_DIR_CHECK='TRUE';
      ALLOW_CONNECT='TRUE';
    'VSS91':
      PIN_NUMBER='(0,0,210)';
      PINUSE='POWER';
      NO_LOAD_CHECK='Both';
      NO_IO_CHECK='Both';
      NO_ASSERT_CHECK='TRUE';
      NO_DIR_CHECK='TRUE';
      ALLOW_CONNECT='TRUE';
    'VSS92':
      PIN_NUMBER='(0,0,212)';
      PINUSE='POWER';
      NO_LOAD_CHECK='Both';
      NO_IO_CHECK='Both';
      NO_ASSERT_CHECK='TRUE';
      NO_DIR_CHECK='TRUE';
      ALLOW_CONNECT='TRUE';
    'VSS93':
      PIN_NUMBER='(0,0,214)';
      PINUSE='POWER';
      NO_LOAD_CHECK='Both';
      NO_IO_CHECK='Both';
      NO_ASSERT_CHECK='TRUE';
      NO_DIR_CHECK='TRUE';
      ALLOW_CONNECT='TRUE';
    'VSS94':
      PIN_NUMBER='(0,0,216)';
      PINUSE='POWER';
      NO_LOAD_CHECK='Both';
      NO_IO_CHECK='Both';
      NO_ASSERT_CHECK='TRUE';
      NO_DIR_CHECK='TRUE';
      ALLOW_CONNECT='TRUE';
    'VSS95':
      PIN_NUMBER='(0,0,219)';
      PINUSE='POWER';
      NO_LOAD_CHECK='Both';
      NO_IO_CHECK='Both';
      NO_ASSERT_CHECK='TRUE';
      NO_DIR_CHECK='TRUE';
      ALLOW_CONNECT='TRUE';
    'VSS96':
      PIN_NUMBER='(0,0,222)';
      PINUSE='POWER';
      NO_LOAD_CHECK='Both';
      NO_IO_CHECK='Both';
      NO_ASSERT_CHECK='TRUE';
      NO_DIR_CHECK='TRUE';
      ALLOW_CONNECT='TRUE';
    'VSS97':
      PIN_NUMBER='(0,0,224)';
      PINUSE='POWER';
      NO_LOAD_CHECK='Both';
      NO_IO_CHECK='Both';
      NO_ASSERT_CHECK='TRUE';
      NO_DIR_CHECK='TRUE';
      ALLOW_CONNECT='TRUE';
    'VSS98':
      PIN_NUMBER='(0,0,226)';
      PINUSE='POWER';
      NO_LOAD_CHECK='Both';
      NO_IO_CHECK='Both';
      NO_ASSERT_CHECK='TRUE';
      NO_DIR_CHECK='TRUE';
      ALLOW_CONNECT='TRUE';
    'VSS99':
      PIN_NUMBER='(0,0,228)';
      PINUSE='POWER';
      NO_LOAD_CHECK='Both';
      NO_IO_CHECK='Both';
      NO_ASSERT_CHECK='TRUE';
      NO_DIR_CHECK='TRUE';
      ALLOW_CONNECT='TRUE';
    'VSS101':
      PIN_NUMBER='(0,0,233)';
      PINUSE='POWER';
      NO_LOAD_CHECK='Both';
      NO_IO_CHECK='Both';
      NO_ASSERT_CHECK='TRUE';
      NO_DIR_CHECK='TRUE';
      ALLOW_CONNECT='TRUE';
    'VSS103':
      PIN_NUMBER='(0,0,237)';
      PINUSE='POWER';
      NO_LOAD_CHECK='Both';
      NO_IO_CHECK='Both';
      NO_ASSERT_CHECK='TRUE';
      NO_DIR_CHECK='TRUE';
      ALLOW_CONNECT='TRUE';
    'VSS105':
      PIN_NUMBER='(0,0,242)';
      PINUSE='POWER';
      NO_LOAD_CHECK='Both';
      NO_IO_CHECK='Both';
      NO_ASSERT_CHECK='TRUE';
      NO_DIR_CHECK='TRUE';
      ALLOW_CONNECT='TRUE';
    'VSS106':
      PIN_NUMBER='(0,0,244)';
      PINUSE='POWER';
      NO_LOAD_CHECK='Both';
      NO_IO_CHECK='Both';
      NO_ASSERT_CHECK='TRUE';
      NO_DIR_CHECK='TRUE';
      ALLOW_CONNECT='TRUE';
    'VSS107':
      PIN_NUMBER='(0,0,246)';
      PINUSE='POWER';
      NO_LOAD_CHECK='Both';
      NO_IO_CHECK='Both';
      NO_ASSERT_CHECK='TRUE';
      NO_DIR_CHECK='TRUE';
      ALLOW_CONNECT='TRUE';
    'VSS108':
      PIN_NUMBER='(0,0,248)';
      PINUSE='POWER';
      NO_LOAD_CHECK='Both';
      NO_IO_CHECK='Both';
      NO_ASSERT_CHECK='TRUE';
      NO_DIR_CHECK='TRUE';
      ALLOW_CONNECT='TRUE';
    'VSS109':
      PIN_NUMBER='(0,0,251)';
      PINUSE='POWER';
      NO_LOAD_CHECK='Both';
      NO_IO_CHECK='Both';
      NO_ASSERT_CHECK='TRUE';
      NO_DIR_CHECK='TRUE';
      ALLOW_CONNECT='TRUE';
    'VSS110':
      PIN_NUMBER='(0,0,253)';
      PINUSE='POWER';
      NO_LOAD_CHECK='Both';
      NO_IO_CHECK='Both';
      NO_ASSERT_CHECK='TRUE';
      NO_DIR_CHECK='TRUE';
      ALLOW_CONNECT='TRUE';
    'VSS111':
      PIN_NUMBER='(0,0,255)';
      PINUSE='POWER';
      NO_LOAD_CHECK='Both';
      NO_IO_CHECK='Both';
      NO_ASSERT_CHECK='TRUE';
      NO_DIR_CHECK='TRUE';
      ALLOW_CONNECT='TRUE';
    'VSS112':
      PIN_NUMBER='(0,0,257)';
      PINUSE='POWER';
      NO_LOAD_CHECK='Both';
      NO_IO_CHECK='Both';
      NO_ASSERT_CHECK='TRUE';
      NO_DIR_CHECK='TRUE';
      ALLOW_CONNECT='TRUE';
    'VSS113':
      PIN_NUMBER='(0,0,259)';
      PINUSE='POWER';
      NO_LOAD_CHECK='Both';
      NO_IO_CHECK='Both';
      NO_ASSERT_CHECK='TRUE';
      NO_DIR_CHECK='TRUE';
      ALLOW_CONNECT='TRUE';
    'VSS114':
      PIN_NUMBER='(0,0,262)';
      PINUSE='POWER';
      NO_LOAD_CHECK='Both';
      NO_IO_CHECK='Both';
      NO_ASSERT_CHECK='TRUE';
      NO_DIR_CHECK='TRUE';
      ALLOW_CONNECT='TRUE';
    'VSS115':
      PIN_NUMBER='(0,0,264)';
      PINUSE='POWER';
      NO_LOAD_CHECK='Both';
      NO_IO_CHECK='Both';
      NO_ASSERT_CHECK='TRUE';
      NO_DIR_CHECK='TRUE';
      ALLOW_CONNECT='TRUE';
    'VSS116':
      PIN_NUMBER='(0,0,266)';
      PINUSE='POWER';
      NO_LOAD_CHECK='Both';
      NO_IO_CHECK='Both';
      NO_ASSERT_CHECK='TRUE';
      NO_DIR_CHECK='TRUE';
      ALLOW_CONNECT='TRUE';
    'VSS117':
      PIN_NUMBER='(0,0,268)';
      PINUSE='POWER';
      NO_LOAD_CHECK='Both';
      NO_IO_CHECK='Both';
      NO_ASSERT_CHECK='TRUE';
      NO_DIR_CHECK='TRUE';
      ALLOW_CONNECT='TRUE';
    'VSS118':
      PIN_NUMBER='(0,0,270)';
      PINUSE='POWER';
      NO_LOAD_CHECK='Both';
      NO_IO_CHECK='Both';
      NO_ASSERT_CHECK='TRUE';
      NO_DIR_CHECK='TRUE';
      ALLOW_CONNECT='TRUE';
    'VSS119':
      PIN_NUMBER='(0,0,273)';
      PINUSE='POWER';
      NO_LOAD_CHECK='Both';
      NO_IO_CHECK='Both';
      NO_ASSERT_CHECK='TRUE';
      NO_DIR_CHECK='TRUE';
      ALLOW_CONNECT='TRUE';
    'VSS120':
      PIN_NUMBER='(0,0,275)';
      PINUSE='POWER';
      NO_LOAD_CHECK='Both';
      NO_IO_CHECK='Both';
      NO_ASSERT_CHECK='TRUE';
      NO_DIR_CHECK='TRUE';
      ALLOW_CONNECT='TRUE';
    'VSS121':
      PIN_NUMBER='(0,0,277)';
      PINUSE='POWER';
      NO_LOAD_CHECK='Both';
      NO_IO_CHECK='Both';
      NO_ASSERT_CHECK='TRUE';
      NO_DIR_CHECK='TRUE';
      ALLOW_CONNECT='TRUE';
    'VSS122':
      PIN_NUMBER='(0,0,279)';
      PINUSE='POWER';
      NO_LOAD_CHECK='Both';
      NO_IO_CHECK='Both';
      NO_ASSERT_CHECK='TRUE';
      NO_DIR_CHECK='TRUE';
      ALLOW_CONNECT='TRUE';
    'VSS123':
      PIN_NUMBER='(0,0,281)';
      PINUSE='POWER';
      NO_LOAD_CHECK='Both';
      NO_IO_CHECK='Both';
      NO_ASSERT_CHECK='TRUE';
      NO_DIR_CHECK='TRUE';
      ALLOW_CONNECT='TRUE';
    'VSS124':
      PIN_NUMBER='(0,0,284)';
      PINUSE='POWER';
      NO_LOAD_CHECK='Both';
      NO_IO_CHECK='Both';
      NO_ASSERT_CHECK='TRUE';
      NO_DIR_CHECK='TRUE';
      ALLOW_CONNECT='TRUE';
    'VSS125':
      PIN_NUMBER='(0,0,286)';
      PINUSE='POWER';
      NO_LOAD_CHECK='Both';
      NO_IO_CHECK='Both';
      NO_ASSERT_CHECK='TRUE';
      NO_DIR_CHECK='TRUE';
      ALLOW_CONNECT='TRUE';
    'VSS126':
      PIN_NUMBER='(0,0,288)';
      PINUSE='POWER';
      NO_LOAD_CHECK='Both';
      NO_IO_CHECK='Both';
      NO_ASSERT_CHECK='TRUE';
      NO_DIR_CHECK='TRUE';
      ALLOW_CONNECT='TRUE';
    'VIN_BULK0':
      PIN_NUMBER='(0,0,1)';
      PINUSE='POWER';
      NO_LOAD_CHECK='Both';
      NO_IO_CHECK='Both';
      NO_ASSERT_CHECK='TRUE';
      NO_DIR_CHECK='TRUE';
      ALLOW_CONNECT='TRUE';
    'VIN_BULK1':
      PIN_NUMBER='(0,0,145)';
      PINUSE='POWER';
      NO_LOAD_CHECK='Both';
      NO_IO_CHECK='Both';
      NO_ASSERT_CHECK='TRUE';
      NO_DIR_CHECK='TRUE';
      ALLOW_CONNECT='TRUE';
    'VIN_BULK2':
      PIN_NUMBER='(0,0,146)';
      PINUSE='POWER';
      NO_LOAD_CHECK='Both';
      NO_IO_CHECK='Both';
      NO_ASSERT_CHECK='TRUE';
      NO_DIR_CHECK='TRUE';
      ALLOW_CONNECT='TRUE';
    'VSS100':
      PIN_NUMBER='(0,0,230)';
      PINUSE='POWER';
      NO_LOAD_CHECK='Both';
      NO_IO_CHECK='Both';
      NO_ASSERT_CHECK='TRUE';
      NO_DIR_CHECK='TRUE';
      ALLOW_CONNECT='TRUE';
    'VSS102':
      PIN_NUMBER='(0,0,235)';
      PINUSE='POWER';
      NO_LOAD_CHECK='Both';
      NO_IO_CHECK='Both';
      NO_ASSERT_CHECK='TRUE';
      NO_DIR_CHECK='TRUE';
      ALLOW_CONNECT='TRUE';
    'VSS104':
      PIN_NUMBER='(0,0,240)';
      PINUSE='POWER';
      NO_LOAD_CHECK='Both';
      NO_IO_CHECK='Both';
      NO_ASSERT_CHECK='TRUE';
      NO_DIR_CHECK='TRUE';
      ALLOW_CONNECT='TRUE';
    'VSS58':
      PIN_NUMBER='(0,0,132)';
      PINUSE='POWER';
      NO_LOAD_CHECK='Both';
      NO_IO_CHECK='Both';
      NO_ASSERT_CHECK='TRUE';
      NO_DIR_CHECK='TRUE';
      ALLOW_CONNECT='TRUE';
    'VSS60':
      PIN_NUMBER='(0,0,136)';
      PINUSE='POWER';
      NO_LOAD_CHECK='Both';
      NO_IO_CHECK='Both';
      NO_ASSERT_CHECK='TRUE';
      NO_DIR_CHECK='TRUE';
      ALLOW_CONNECT='TRUE';
    'VSS61':
      PIN_NUMBER='(0,0,139)';
      PINUSE='POWER';
      NO_LOAD_CHECK='Both';
      NO_IO_CHECK='Both';
      NO_ASSERT_CHECK='TRUE';
      NO_DIR_CHECK='TRUE';
      ALLOW_CONNECT='TRUE';
    'VSS62':
      PIN_NUMBER='(0,0,141)';
      PINUSE='POWER';
      NO_LOAD_CHECK='Both';
      NO_IO_CHECK='Both';
      NO_ASSERT_CHECK='TRUE';
      NO_DIR_CHECK='TRUE';
      ALLOW_CONNECT='TRUE';
    'G1':
      PIN_NUMBER='(0,0,G1)';
      PINUSE='POWER';
      NO_LOAD_CHECK='Both';
      NO_IO_CHECK='Both';
      NO_ASSERT_CHECK='TRUE';
      NO_DIR_CHECK='TRUE';
      ALLOW_CONNECT='TRUE';
    'G2':
      PIN_NUMBER='(0,0,G2)';
      PINUSE='POWER';
      NO_LOAD_CHECK='Both';
      NO_IO_CHECK='Both';
      NO_ASSERT_CHECK='TRUE';
      NO_DIR_CHECK='TRUE';
      ALLOW_CONNECT='TRUE';
    'G3':
      PIN_NUMBER='(0,0,G3)';
      PINUSE='POWER';
      NO_LOAD_CHECK='Both';
      NO_IO_CHECK='Both';
      NO_ASSERT_CHECK='TRUE';
      NO_DIR_CHECK='TRUE';
      ALLOW_CONNECT='TRUE';
  end_pin;
  body
    PART_NAME='SCONN288_DDR506112002KQ';
    BODY_NAME='SCONN288_DDR506112002KQ';
    PHYS_DES_PREFIX='J';
    CLASS='IO';
  end_body;
end_primitive;

END.
